FILE_TYPE=LIBRARY_PARTS;
primitive 'SC2K2P50V3KX-GP_SMD-BCG6';
  pin
    '1':
      PIN_NUMBER='(1)';
      PIN_TYPE='ANALOG';
      NO_LOAD_CHECK='Both';
      NO_IO_CHECK='Both';
      NO_ASSERT_CHECK='TRUE';
      NO_DIR_CHECK='TRUE';
      ALLOW_CONNECT='TRUE';
    '2':
      PIN_NUMBER='(2)';
      PIN_TYPE='ANALOG';
      NO_LOAD_CHECK='Both';
      NO_IO_CHECK='Both';
      NO_ASSERT_CHECK='TRUE';
      NO_DIR_CHECK='TRUE';
      ALLOW_CONNECT='TRUE';
  end_pin;
  body
    PART_NAME='SC2K2P50V3KX-GP';
    BODY_NAME='SC2K2P50V3KX-GP';
    PHYS_DES_PREFIX='C';
    CLASS='DISCRETE';
  end_body;
end_primitive;

END.
